(kicad_pcb
	(version 20241229)
	(generator "pcbnew")
	(generator_version "9.0")
	(general
		(thickness 1.63)
		(legacy_teardrops no)
	)
	(paper "A4")
	(title_block
		(title "CM4 Baseboard")
		(date "2026-01-05")
		(rev "1.1.1")
		(company "Antmicro Ltd")
		(comment 1 "www.antmicro.com")
		(comment 9 "footprints 330-333 of 506")
	)
	(layers
		(0 "F.Cu" signal)
		(4 "In1.Cu" power)
		(6 "In2.Cu" power)
		(8 "In3.Cu" signal)
		(10 "In4.Cu" signal)
		(2 "B.Cu" signal)
		(9 "F.Adhes" user "F.Adhesive")
		(11 "B.Adhes" user "B.Adhesive")
		(13 "F.Paste" user)
		(15 "B.Paste" user)
		(5 "F.SilkS" user "F.Silkscreen")
		(7 "B.SilkS" user "B.Silkscreen")
		(1 "F.Mask" user)
		(3 "B.Mask" user)
		(17 "Dwgs.User" user "User.Drawings")
		(19 "Cmts.User" user "User.Comments")
		(21 "Eco1.User" user "User.Eco1")
		(23 "Eco2.User" user "User.Eco2")
		(25 "Edge.Cuts" user)
		(27 "Margin" user)
		(31 "F.CrtYd" user "F.Courtyard")
		(29 "B.CrtYd" user "B.Courtyard")
		(35 "F.Fab" user)
		(33 "B.Fab" user)
	)
	(footprint "antmicro-footprints:R_0402_1005Metric"
		(layer "B.Cu")
		(at 87.267962 163.7565)
		(descr "Resistor SMD 0402")
		(tags "resistor SMD 0402")
		(property "Reference" "R206"
			(at -1.77 -0.67 0)
			(layer "B.SilkS")
			(effects
				(font
					(size 0.7 0.7)
					(thickness 0.15)
				)
				(justify right bottom mirror)
			)
		)
		(property "Value" "R_0R_0402"
			(at -1.011843 -1.772047 0)
			(layer "B.Fab")
			(effects
				(font
					(size 0.7 0.7)
					(thickness 0.15)
				)
				(justify right bottom mirror)
			)
		)
		(property "Datasheet" "https://industrial.panasonic.com/cdbs/www-data/pdf/RDA0000/AOA0000C301.pdf"
			(at 0 0 0)
			(layer "B.Fab")
			(hide yes)
			(effects
				(font
					(size 1.27 1.27)
					(thickness 0.15)
				)
			)
		)
		(property "Manufacturer" "Panasonic"
			(at 0 0 0)
			(unlocked yes)
			(layer "B.Fab")
			(hide yes)
			(effects
				(font
					(size 1 1)
					(thickness 0.15)
				)
				(justify mirror)
			)
		)
		(property "MPN" "ERJ2GE0R00X"
			(at 0 0 0)
			(unlocked yes)
			(layer "B.Fab")
			(hide yes)
			(effects
				(font
					(size 1 1)
					(thickness 0.15)
				)
				(justify mirror)
			)
		)
		(property "Val" "0R"
			(at 0 0 0)
			(unlocked yes)
			(layer "B.Fab")
			(hide yes)
			(effects
				(font
					(size 1 1)
					(thickness 0.15)
				)
				(justify mirror)
			)
		)
		(property "License" "Apache-2.0"
			(at 0 0 0)
			(unlocked yes)
			(layer "B.Fab")
			(hide yes)
			(effects
				(font
					(size 1 1)
					(thickness 0.15)
				)
				(justify mirror)
			)
		)
		(property "Author" "Antmicro"
			(at 0 0 0)
			(unlocked yes)
			(layer "B.Fab")
			(hide yes)
			(effects
				(font
					(size 1 1)
					(thickness 0.15)
				)
				(justify mirror)
			)
		)
		(property "Tolerance" "~"
			(at 0 0 0)
			(unlocked yes)
			(layer "B.Fab")
			(hide yes)
			(effects
				(font
					(size 1 1)
					(thickness 0.15)
				)
				(justify mirror)
			)
		)
		(property "Current" "1A"
			(at 0 0 0)
			(unlocked yes)
			(layer "B.Fab")
			(hide yes)
			(effects
				(font
					(size 1 1)
					(thickness 0.15)
				)
				(justify mirror)
			)
		)
		(sheetname "/Compute module/")
		(sheetfile "compute-module.kicad_sch")
		(attr smd exclude_from_pos_files exclude_from_bom dnp)
		(fp_rect
			(start -0.925 0.47)
			(end 0.925 -0.47)
			(stroke
				(width 0.05)
				(type default)
			)
			(fill no)
			(layer "B.CrtYd")
		)
		(fp_rect
			(start -0.5 0.25)
			(end 0.5 -0.25)
			(stroke
				(width 0.15)
				(type solid)
			)
			(fill no)
			(layer "B.Fab")
		)
		(fp_text user "License: Apache-2.0"
			(at -0.95 -5.169 180)
			(layer "B.Fab")
			(effects
				(font
					(size 0.7 0.7)
					(thickness 0.15)
				)
				(justify left bottom mirror)
			)
		)
		(fp_text user "${REFERENCE}"
			(at -0.95 -3.168 180)
			(layer "B.Fab")
			(effects
				(font
					(size 0.7 0.7)
					(thickness 0.15)
				)
				(justify left bottom mirror)
			)
		)
		(fp_text user "Author: Antmicro"
			(at -0.95 -4.169 180)
			(layer "B.Fab")
			(effects
				(font
					(size 0.7 0.7)
					(thickness 0.15)
				)
				(justify left bottom mirror)
			)
		)
		(pad "1" smd roundrect
			(at -0.48 0)
			(size 0.59 0.64)
			(layers "B.Cu" "B.Mask" "B.Paste")
			(roundrect_rratio 0.25)
			(net 130 "Net-(J201-Pad76)")
			(pintype "passive")
		)
		(pad "2" smd roundrect
			(at 0.48 0)
			(size 0.59 0.64)
			(layers "B.Cu" "B.Mask" "B.Paste")
			(roundrect_rratio 0.25)
			(net 118 "/Compute module/SDIO.CD")
			(pintype "passive")
		)
	)
	(footprint "antmicro-footprints:C_0402_1005Metric"
		(layer "B.Cu")
		(at 112.967962 131.9865 180)
		(descr "Capacitor SMD 0402")
		(tags "capacitor SMD 0402")
		(property "Reference" "C308"
			(at -3.53 -0.395 0)
			(layer "B.SilkS")
			(effects
				(font
					(size 0.7 0.7)
					(thickness 0.15)
				)
				(justify left bottom mirror)
			)
		)
		(property "Value" "C_100n_0402"
			(at -1.022927 -2.155213 0)
			(layer "B.Fab")
			(effects
				(font
					(size 0.7 0.7)
					(thickness 0.15)
				)
				(justify left bottom mirror)
			)
		)
		(property "Datasheet" "https://www.murata.com/products/productdetail?partno=GRM155R61H104KE14%23"
			(at 0 0 180)
			(layer "B.Fab")
			(hide yes)
			(effects
				(font
					(size 1.27 1.27)
					(thickness 0.15)
				)
			)
		)
		(property "Manufacturer" "Murata"
			(at 0 0 180)
			(unlocked yes)
			(layer "B.Fab")
			(hide yes)
			(effects
				(font
					(size 1 1)
					(thickness 0.15)
				)
				(justify mirror)
			)
		)
		(property "MPN" "GRM155R61H104KE14D"
			(at 0 0 180)
			(unlocked yes)
			(layer "B.Fab")
			(hide yes)
			(effects
				(font
					(size 1 1)
					(thickness 0.15)
				)
				(justify mirror)
			)
		)
		(property "Val" "100n"
			(at 0 0 180)
			(unlocked yes)
			(layer "B.Fab")
			(hide yes)
			(effects
				(font
					(size 1 1)
					(thickness 0.15)
				)
				(justify mirror)
			)
		)
		(property "License" "Apache-2.0"
			(at 0 0 180)
			(unlocked yes)
			(layer "B.Fab")
			(hide yes)
			(effects
				(font
					(size 1 1)
					(thickness 0.15)
				)
				(justify mirror)
			)
		)
		(property "Author" "Antmicro"
			(at 0 0 180)
			(unlocked yes)
			(layer "B.Fab")
			(hide yes)
			(effects
				(font
					(size 1 1)
					(thickness 0.15)
				)
				(justify mirror)
			)
		)
		(property "Voltage" "50V"
			(at 0 0 180)
			(unlocked yes)
			(layer "B.Fab")
			(hide yes)
			(effects
				(font
					(size 1 1)
					(thickness 0.15)
				)
				(justify mirror)
			)
		)
		(property "Dielectric" "X5R"
			(at 0 0 180)
			(unlocked yes)
			(layer "B.Fab")
			(hide yes)
			(effects
				(font
					(size 1 1)
					(thickness 0.15)
				)
				(justify mirror)
			)
		)
		(sheetname "/Supply/")
		(sheetfile "supply.kicad_sch")
		(attr smd)
		(fp_rect
			(start -0.925 0.47)
			(end 0.925 -0.47)
			(stroke
				(width 0.05)
				(type default)
			)
			(fill no)
			(layer "B.CrtYd")
		)
		(fp_line
			(start 0.504 0.25)
			(end 0.504 -0.248)
			(stroke
				(width 0.15)
				(type solid)
			)
			(layer "B.Fab")
		)
		(fp_line
			(start 0.504 -0.248)
			(end -0.494 -0.248)
			(stroke
				(width 0.15)
				(type solid)
			)
			(layer "B.Fab")
		)
		(fp_line
			(start -0.494 0.25)
			(end 0.504 0.25)
			(stroke
				(width 0.15)
				(type solid)
			)
			(layer "B.Fab")
		)
		(fp_line
			(start -0.494 -0.248)
			(end -0.494 0.25)
			(stroke
				(width 0.15)
				(type solid)
			)
			(layer "B.Fab")
		)
		(fp_text user "Author: Antmicro"
			(at -0.939 -3.399 0)
			(layer "B.Fab")
			(effects
				(font
					(size 0.7 0.7)
					(thickness 0.15)
				)
				(justify left bottom mirror)
			)
		)
		(fp_text user "${REFERENCE}"
			(at -0.939 -4.599 0)
			(layer "B.Fab")
			(effects
				(font
					(size 0.7 0.7)
					(thickness 0.15)
				)
				(justify left bottom mirror)
			)
		)
		(fp_text user "License: Apache-2.0"
			(at -0.939 -5.799 0)
			(layer "B.Fab")
			(effects
				(font
					(size 0.7 0.7)
					(thickness 0.15)
				)
				(justify left bottom mirror)
			)
		)
		(pad "1" smd roundrect
			(at -0.48 0 180)
			(size 0.59 0.64)
			(layers "B.Cu" "B.Mask" "B.Paste")
			(roundrect_rratio 0.25)
			(net 45 "/Supply/SW_M2")
			(pintype "passive")
		)
		(pad "2" smd roundrect
			(at 0.48 0 180)
			(size 0.59 0.64)
			(layers "B.Cu" "B.Mask" "B.Paste")
			(roundrect_rratio 0.25)
			(net 48 "Net-(U301-BST)")
			(pintype "passive")
		)
	)
	(footprint "antmicro-footprints:SOD-523"
		(layer "B.Cu")
		(at 135.717962 148.6665 -90)
		(property "Reference" "D604"
			(at 1 -0.47 90)
			(layer "B.SilkS")
			(effects
				(font
					(size 0.7 0.7)
					(thickness 0.15)
				)
				(justify left bottom mirror)
			)
		)
		(property "Value" "PESD5Z5_0F"
			(at 0 -1.499 90)
			(layer "B.Fab")
			(effects
				(font
					(size 0.7 0.7)
					(thickness 0.15)
				)
				(justify left bottom mirror)
			)
		)
		(property "Datasheet" "https://assets.nexperia.com/documents/data-sheet/PESD5Z5_0.pdf"
			(at 0 0 270)
			(layer "B.Fab")
			(hide yes)
			(effects
				(font
					(size 1.27 1.27)
					(thickness 0.15)
				)
			)
		)
		(property "Manufacturer" "Nexperia"
			(at 0 0 270)
			(unlocked yes)
			(layer "B.Fab")
			(hide yes)
			(effects
				(font
					(size 1 1)
					(thickness 0.15)
				)
				(justify mirror)
			)
		)
		(property "MPN" "PESD5Z5.0F"
			(at 0 0 270)
			(unlocked yes)
			(layer "B.Fab")
			(hide yes)
			(effects
				(font
					(size 1 1)
					(thickness 0.15)
				)
				(justify mirror)
			)
		)
		(property "Author" "Antmicro"
			(at 0 0 270)
			(unlocked yes)
			(layer "B.Fab")
			(hide yes)
			(effects
				(font
					(size 1 1)
					(thickness 0.15)
				)
				(justify mirror)
			)
		)
		(property "License" "Apache-2.0"
			(at 0 0 270)
			(unlocked yes)
			(layer "B.Fab")
			(hide yes)
			(effects
				(font
					(size 1 1)
					(thickness 0.15)
				)
				(justify mirror)
			)
		)
		(sheetname "/CSI/")
		(sheetfile "csi.kicad_sch")
		(attr smd)
		(fp_line
			(start -0.35 0.5)
			(end -0.35 -0.5)
			(stroke
				(width 0.15)
				(type solid)
			)
			(layer "B.SilkS")
		)
		(fp_rect
			(start -1 0.6)
			(end 1 -0.6)
			(stroke
				(width 0.05)
				(type solid)
			)
			(fill no)
			(layer "B.CrtYd")
		)
		(fp_line
			(start -0.652 0.425)
			(end 0.65 0.425)
			(stroke
				(width 0.15)
				(type solid)
			)
			(layer "B.Fab")
		)
		(fp_line
			(start 0.65 0.425)
			(end 0.65 -0.423)
			(stroke
				(width 0.15)
				(type solid)
			)
			(layer "B.Fab")
		)
		(fp_line
			(start -0.35 0.4)
			(end -0.35 -0.4)
			(stroke
				(width 0.15)
				(type solid)
			)
			(layer "B.Fab")
		)
		(fp_line
			(start -0.652 -0.423)
			(end -0.652 0.425)
			(stroke
				(width 0.15)
				(type solid)
			)
			(layer "B.Fab")
		)
		(fp_line
			(start -0.652 -0.423)
			(end 0.65 -0.423)
			(stroke
				(width 0.15)
				(type solid)
			)
			(layer "B.Fab")
		)
		(fp_text user "License: Apache-2.0"
			(at -1.276 -5.9 90)
			(layer "B.Fab")
			(effects
				(font
					(size 0.7 0.7)
					(thickness 0.15)
				)
				(justify left bottom mirror)
			)
		)
		(fp_text user "Author: Antmicro"
			(at -1.276 -4.7 90)
			(layer "B.Fab")
			(effects
				(font
					(size 0.7 0.7)
					(thickness 0.15)
				)
				(justify left bottom mirror)
			)
		)
		(fp_text user "${REFERENCE}"
			(at -1.276 -3.499 90)
			(layer "B.Fab")
			(effects
				(font
					(size 0.7 0.7)
					(thickness 0.15)
				)
				(justify left bottom mirror)
			)
		)
		(pad "1" smd roundrect
			(at -0.701 0 270)
			(size 0.5 0.6)
			(layers "B.Cu" "B.Mask" "B.Paste")
			(roundrect_rratio 0.25)
			(net 20 "/CSI/CSI_5V")
			(pinfunction "C")
			(pintype "passive")
		)
		(pad "2" smd roundrect
			(at 0.699 0 270)
			(size 0.5 0.6)
			(layers "B.Cu" "B.Mask" "B.Paste")
			(roundrect_rratio 0.25)
			(net 3 "GND")
			(pinfunction "A")
			(pintype "passive")
		)
	)
	(footprint "antmicro-footprints:Nexperia_DFN-10_2.5x1mm_P0.5mm"
		(layer "B.Cu")
		(at 89.505962 175.1915 90)
		(property "Reference" "D701"
			(at -1.198 -1.908 90)
			(layer "B.SilkS")
			(effects
				(font
					(size 0.7 0.7)
					(thickness 0.15)
				)
				(justify right bottom mirror)
			)
		)
		(property "Value" "PUSB3F96X_PASS"
			(at -0.016 -1.705 90)
			(layer "B.Fab")
			(effects
				(font
					(size 0.7 0.7)
					(thickness 0.15)
				)
				(justify right bottom mirror)
			)
		)
		(property "Datasheet" "https://mouser.com/datasheet/2/916/PUSB3F96-1600324.pdf"
			(at 0 0 90)
			(layer "B.Fab")
			(hide yes)
			(effects
				(font
					(size 1.27 1.27)
					(thickness 0.15)
				)
			)
		)
		(property "Manufacturer" "Nexperia"
			(at 0 0 90)
			(unlocked yes)
			(layer "B.Fab")
			(hide yes)
			(effects
				(font
					(size 1 1)
					(thickness 0.15)
				)
				(justify mirror)
			)
		)
		(property "MPN" "PUSB3F96X"
			(at 0 0 90)
			(unlocked yes)
			(layer "B.Fab")
			(hide yes)
			(effects
				(font
					(size 1 1)
					(thickness 0.15)
				)
				(justify mirror)
			)
		)
		(property "Author" "Antmicro"
			(at 0 0 90)
			(unlocked yes)
			(layer "B.Fab")
			(hide yes)
			(effects
				(font
					(size 1 1)
					(thickness 0.15)
				)
				(justify mirror)
			)
		)
		(property "License" "Apache-2.0"
			(at 0 0 90)
			(unlocked yes)
			(layer "B.Fab")
			(hide yes)
			(effects
				(font
					(size 1 1)
					(thickness 0.15)
				)
				(justify mirror)
			)
		)
		(sheetname "/Display/")
		(sheetfile "display.kicad_sch")
		(attr smd)
		(fp_line
			(start 1.375 -0.4)
			(end 1.375 0.4)
			(stroke
				(width 0.15)
				(type solid)
			)
			(layer "B.SilkS")
		)
		(fp_line
			(start -1.375 0.4)
			(end -1.375 -0.4)
			(stroke
				(width 0.15)
				(type solid)
			)
			(layer "B.SilkS")
		)
		(fp_circle
			(center -1.4 -0.7)
			(end -1.349 -0.7)
			(stroke
				(width 0.15)
				(type solid)
			)
			(fill yes)
			(layer "B.SilkS")
		)
		(fp_rect
			(start -1.4 0.725)
			(end 1.4 -0.725)
			(stroke
				(width 0.05)
				(type solid)
			)
			(fill no)
			(layer "B.CrtYd")
		)
		(fp_line
			(start 1.25 -0.5)
			(end 1.25 0.5)
			(stroke
				(width 0.15)
				(type solid)
			)
			(layer "B.Fab")
		)
		(fp_line
			(start -0.9 -0.5)
			(end 1.25 -0.5)
			(stroke
				(width 0.15)
				(type solid)
			)
			(layer "B.Fab")
		)
		(fp_line
			(start -1.25 -0.15)
			(end -0.9 -0.5)
			(stroke
				(width 0.15)
				(type solid)
			)
			(layer "B.Fab")
		)
		(fp_line
			(start 1.25 0.5)
			(end -1.25 0.5)
			(stroke
				(width 0.15)
				(type solid)
			)
			(layer "B.Fab")
		)
		(fp_line
			(start -1.25 0.5)
			(end -1.25 -0.15)
			(stroke
				(width 0.15)
				(type solid)
			)
			(layer "B.Fab")
		)
		(fp_text user "License: Apache-2.0"
			(at -1.367 -6.105 270)
			(layer "B.Fab")
			(effects
				(font
					(size 0.7 0.7)
					(thickness 0.15)
				)
				(justify left bottom mirror)
			)
		)
		(fp_text user "${REFERENCE}"
			(at -1.367 -3.704 270)
			(layer "B.Fab")
			(effects
				(font
					(size 0.7 0.7)
					(thickness 0.15)
				)
				(justify left bottom mirror)
			)
		)
		(fp_text user "Author: Antmicro"
			(at -1.367 -4.905 270)
			(layer "B.Fab")
			(effects
				(font
					(size 0.7 0.7)
					(thickness 0.15)
				)
				(justify left bottom mirror)
			)
		)
		(pad "1" smd rect
			(at -1 -0.3875 90)
			(size 0.2 0.475)
			(layers "B.Cu" "B.Mask" "B.Paste")
			(net 96 "/Compute module/DSI.D3_N")
			(pinfunction "CH1")
			(pintype "passive")
			(solder_mask_margin 0.05)
		)
		(pad "2" smd rect
			(at -0.5 -0.3875 90)
			(size 0.2 0.475)
			(layers "B.Cu" "B.Mask" "B.Paste")
			(net 98 "/Compute module/DSI.D3_P")
			(pinfunction "CH2")
			(pintype "passive")
			(solder_mask_margin 0.05)
		)
		(pad "3" smd rect
			(at 0 -0.3875 90)
			(size 0.2 0.475)
			(layers "B.Cu" "B.Mask" "B.Paste")
			(net 3 "GND")
			(pinfunction "GND")
			(pintype "passive")
			(solder_mask_margin 0.05)
		)
		(pad "4" smd rect
			(at 0.5 -0.3875 90)
			(size 0.2 0.475)
			(layers "B.Cu" "B.Mask" "B.Paste")
			(net 87 "/Compute module/DSI.D2_N")
			(pinfunction "CH3")
			(pintype "passive")
			(solder_mask_margin 0.05)
		)
		(pad "5" smd rect
			(at 1 -0.3875 90)
			(size 0.2 0.475)
			(layers "B.Cu" "B.Mask" "B.Paste")
			(net 97 "/Compute module/DSI.D2_P")
			(pinfunction "CH4")
			(pintype "passive")
			(solder_mask_margin 0.05)
		)
		(pad "6" smd rect
			(at 1 0.3875 90)
			(size 0.2 0.475)
			(layers "B.Cu" "B.Mask" "B.Paste")
			(net 97 "/Compute module/DSI.D2_P")
			(pinfunction "CH4")
			(pintype "passive")
			(solder_mask_margin 0.05)
		)
		(pad "7" smd rect
			(at 0.5 0.3875 90)
			(size 0.2 0.475)
			(layers "B.Cu" "B.Mask" "B.Paste")
			(net 87 "/Compute module/DSI.D2_N")
			(pinfunction "CH3")
			(pintype "passive")
			(solder_mask_margin 0.05)
		)
		(pad "8" smd rect
			(at 0 0.3875 90)
			(size 0.2 0.475)
			(layers "B.Cu" "B.Mask" "B.Paste")
			(net 3 "GND")
			(pinfunction "GND")
			(pintype "passive")
			(solder_mask_margin 0.05)
		)
		(pad "9" smd rect
			(at -0.501 0.3875 90)
			(size 0.2 0.475)
			(layers "B.Cu" "B.Mask" "B.Paste")
			(net 98 "/Compute module/DSI.D3_P")
			(pinfunction "CH2")
			(pintype "passive")
			(solder_mask_margin 0.05)
		)
		(pad "10" smd rect
			(at -1 0.3875 90)
			(size 0.2 0.475)
			(layers "B.Cu" "B.Mask" "B.Paste")
			(net 96 "/Compute module/DSI.D3_N")
			(pinfunction "CH1")
			(pintype "passive")
			(solder_mask_margin 0.05)
		)
	)
)
